# S9S_MB_2U (Grand Teton) — schematic parts with pin connectivity, parts 1619–1619 of 6093; source: Cadence DE-HDL packaged netlist (pstxprt.dat, pstxnet.dat, pstchip.dat)

J26  SCONN288_ADR50017P087CC  SCONN288_ADR50017-P087CC IO  pkg DDR288S_1-1VXB  page 107
  1  VIN_BULK0  POWER  = P12V_S3_AUX_CPU1_NVDIMM
  2  RFU0  TRI  = TP_CHE_CPU1_DIMM2_FRU_0
  3  VIN_MGMT  POWER  = P3V3_AUX
  4  HSCL  IN  = I3C_SPD_DDREFGH_CPU1_LVC1_SCL_1
  5  HSDA  BI  = I3C_SPD_DDREFGH_CPU1_LVC1_SDA
  6  VSS0  POWER  = GND
  7  DQ0_A  BI  = M_E_CPU1_SA_DQ<0>
  8  VSS1  POWER  = GND
  9  DQ1_A  BI  = M_E_CPU1_SA_DQ<1>
  10  VSS2  POWER  = GND
  11  DQS0_A_T  BI  = M_E_CPU1_SA_DQS_DP<0>
  12  DQS0_A_C  BI  = M_E_CPU1_SA_DQS_DN<0>
  13  VSS3  POWER  = GND
  14  DQ4_A  BI  = M_E_CPU1_SA_DQ<4>
  15  VSS4  POWER  = GND
  16  DQ5_A  BI  = M_E_CPU1_SA_DQ<5>
  17  VSS5  POWER  = GND
  18  DQ8_A  BI  = M_E_CPU1_SA_DQ<8>
  19  VSS6  POWER  = GND
  20  DQ9_A  BI  = M_E_CPU1_SA_DQ<9>
  21  VSS7  POWER  = GND
  22  DQS1_A_T  BI  = M_E_CPU1_SA_DQS_DP<1>
  23  DQS1_A_C  BI  = M_E_CPU1_SA_DQS_DN<1>
  24  VSS8  POWER  = GND
  25  DQ12_A  BI  = M_E_CPU1_SA_DQ<12>
  26  VSS9  POWER  = GND
  27  DQ13_A  BI  = M_E_CPU1_SA_DQ<13>
  28  VSS10  POWER  = GND
  29  DQ16_A  BI  = M_E_CPU1_SA_DQ<16>
  30  VSS11  POWER  = GND
  31  DQ17_A  BI  = M_E_CPU1_SA_DQ<17>
  32  VSS12  POWER  = GND
  33  DQS2_A_T  BI  = M_E_CPU1_SA_DQS_DP<2>
  34  DQS2_A_C  BI  = M_E_CPU1_SA_DQS_DN<2>
  35  VSS13  POWER  = GND
  36  DQ20_A  BI  = M_E_CPU1_SA_DQ<20>
  37  VSS14  POWER  = GND
  38  DQ21_A  BI  = M_E_CPU1_SA_DQ<21>
  39  VSS15  POWER  = GND
  40  DQ24_A  BI  = M_E_CPU1_SA_DQ<24>
  41  VSS16  POWER  = GND
  42  DQ25_A  BI  = M_E_CPU1_SA_DQ<25>
  43  VSS17  POWER  = GND
  44  DQS3_A_T  BI  = M_E_CPU1_SA_DQS_DP<3>
  45  DQS3_A_C  BI  = M_E_CPU1_SA_DQS_DN<3>
  46  VSS18  POWER  = GND
  47  DQ28_A  BI  = M_E_CPU1_SA_DQ<28>
  48  VSS19  POWER  = GND
  49  DQ29_A  BI  = M_E_CPU1_SA_DQ<29>
  50  VSS20  POWER  = GND
  51  CB0_A  BI  = M_E_CPU1_SA_CB<0>
  52  VSS21  POWER  = GND
  53  CB1_A  BI  = M_E_CPU1_SA_CB<1>
  54  VSS22  POWER  = GND
  55  DQS4_A_T  BI  = M_E_CPU1_SA_DQS_DP<4>
  56  DQS4_A_C  BI  = M_E_CPU1_SA_DQS_DN<4>
  57  VSS23  POWER  = GND
  58  CB4_A  BI  = M_E_CPU1_SA_CB<4>
  59  VSS24  POWER  = GND
  60  CB5_A  BI  = M_E_CPU1_SA_CB<5>
  61  VSS25  POWER  = GND
  62  ALERT_N  OUT  = M_E_CPU1_ALERT_N
  63  VSS26  POWER  = GND
  64  CS0_A_N  IN  = M_E_CPU1_SA_CS_N<2>
  65  VSS27  POWER  = GND
  66  CA0_A  IN  = M_E_CPU1_SA_CA<0>
  67  VSS28  POWER  = GND
  68  CA2_A  IN  = M_E_CPU1_SA_CA<2>
  69  VSS29  POWER  = GND
  70  CA4_A  IN  = M_E_CPU1_SA_CA<4>
  71  VSS30  POWER  = GND
  72  CA6_A  IN  = M_E_CPU1_SA_CA<6>
  73  VSS31  POWER  = GND
  74  PAR_A  IN  = M_E_CPU1_SA_PAR
  75  VSS32  POWER  = GND
  76  CA0_B  IN  = M_E_CPU1_SB_CA<0>
  77  VSS33  POWER  = GND
  78  CA2_B  IN  = M_E_CPU1_SB_CA<2>
  79  VSS34  POWER  = GND
  80  CA4_B  IN  = M_E_CPU1_SB_CA<4>
  81  VSS35  POWER  = GND
  82  CA6_B  IN  = M_E_CPU1_SB_CA<6>
  83  VSS36  POWER  = GND
  84  CS0_B_N  IN  = M_E_CPU1_SB_CS_N<2>
  85  VSS37  POWER  = GND
  86  \lbd||rsp_a_n\  OUT  = M_E_CPU1_SA_RSP<1>
  87  \lbs||rsp_b_n\  OUT  = M_E_CPU1_SB_RSP<1>
  88  VSS38  POWER  = GND
  89  CB4_B  BI  = M_E_CPU1_SB_CB<4>
  90  VSS39  POWER  = GND
  91  CB5_B  BI  = M_E_CPU1_SB_CB<5>
  92  VSS40  POWER  = GND
  93  \dqs9_b_t||tdqs9_b_t||dbi4_b_n\  BI  = M_E_CPU1_SB_DQS_DP<9>
  94  \dqs9_b_c||tdqs9_b_c\  BI  = M_E_CPU1_SB_DQS_DN<9>
  95  VSS41  POWER  = GND
  96  CB0_B  BI  = M_E_CPU1_SB_CB<0>
  97  VSS42  POWER  = GND
  98  CB1_B  BI  = M_E_CPU1_SB_CB<1>
  99  VSS43  POWER  = GND
  100  DQ0_B  BI  = M_E_CPU1_SB_DQ<0>
  101  VSS44  POWER  = GND
  102  DQ1_B  BI  = M_E_CPU1_SB_DQ<1>
  103  VSS45  POWER  = GND
  104  DQS0_B_T  BI  = M_E_CPU1_SB_DQS_DP<0>
  105  DQS0_B_C  BI  = M_E_CPU1_SB_DQS_DN<0>
  106  VSS46  POWER  = GND
  107  DQ4_B  BI  = M_E_CPU1_SB_DQ<4>
  108  VSS47  POWER  = GND
  109  DQ5_B  BI  = M_E_CPU1_SB_DQ<5>
  110  VSS48  POWER  = GND
  111  DQ8_B  BI  = M_E_CPU1_SB_DQ<8>
  112  VSS49  POWER  = GND
  113  DQ9_B  BI  = M_E_CPU1_SB_DQ<9>
  114  VSS50  POWER  = GND
  115  DQS1_B_T  BI  = M_E_CPU1_SB_DQS_DP<1>
  116  DQS1_B_C  BI  = M_E_CPU1_SB_DQS_DN<1>
  117  VSS51  POWER  = GND
  118  DQ12_B  BI  = M_E_CPU1_SB_DQ<12>
  119  VSS52  POWER  = GND
  120  DQ13_B  BI  = M_E_CPU1_SB_DQ<13>
  121  VSS53  POWER  = GND
  122  DQ16_B  BI  = M_E_CPU1_SB_DQ<16>
  123  VSS54  POWER  = GND
  124  DQ17_B  BI  = M_E_CPU1_SB_DQ<17>
  125  VSS55  POWER  = GND
  126  DQS2_B_T  BI  = M_E_CPU1_SB_DQS_DP<2>
  127  DQS2_B_C  BI  = M_E_CPU1_SB_DQS_DN<2>
  128  VSS56  POWER  = GND
  129  DQ20_B  BI  = M_E_CPU1_SB_DQ<20>
  130  VSS57  POWER  = GND
  131  DQ21_B  BI  = M_E_CPU1_SB_DQ<21>
  132  VSS58  POWER  = GND
  133  DQ24_B  BI  = M_E_CPU1_SB_DQ<24>
  134  VSS59  POWER  = GND
  135  DQ25_B  BI  = M_E_CPU1_SB_DQ<25>
  136  VSS60  POWER  = GND
  137  DQS3_B_T  BI  = M_E_CPU1_SB_DQS_DP<3>
  138  DQS3_B_C  BI  = M_E_CPU1_SB_DQS_DN<3>
  139  VSS61  POWER  = GND
  140  DQ28_B  BI  = M_E_CPU1_SB_DQ<28>
  141  VSS62  POWER  = GND
  142  DQ29_B  BI  = M_E_CPU1_SB_DQ<29>
  143  VSS63  POWER  = GND
  144  RFU1  TRI  = TP_CHE_CPU1_DIMM2_FRU_1
  145  VIN_BULK1  POWER  = P12V_S3_AUX_CPU1_NVDIMM
  146  VIN_BULK2  POWER  = P12V_S3_AUX_CPU1_NVDIMM
  147  \pwr_good||fail_n\  BI  = PWRGD_CHE_CPU1_DIMM2
  148  HSA  IN  = PD_CHE_CPU1_DIMM2_SAA
  149  RFU2  TRI  = TP_CHE_CPU1_DIMM2_FRU_2
  150  RFU3  TRI  = TP_CHE_CPU1_DIMM2_FRU_3
  151  VSS64  POWER  = GND
  152  DQ2_A  BI  = M_E_CPU1_SA_DQ<2>
  153  VSS65  POWER  = GND
  154  DQ3_A  BI  = M_E_CPU1_SA_DQ<3>
  155  VSS66  POWER  = GND
  156  \dqs5_a_c||tdqs5_a_c||dqs5_a_t||tdqs5_a_t\  BI  = M_E_CPU1_SA_DQS_DN<5>
  157  \dqs5_a_t||tdqs5_a_t\  BI  = M_E_CPU1_SA_DQS_DP<5>
  158  VSS67  POWER  = GND
  159  DQ6_A  BI  = M_E_CPU1_SA_DQ<6>
  160  VSS68  POWER  = GND
  161  DQ7_A  BI  = M_E_CPU1_SA_DQ<7>
  162  VSS69  POWER  = GND
  163  DQ10_A  BI  = M_E_CPU1_SA_DQ<10>
  164  VSS70  POWER  = GND
  165  DQ11_A  BI  = M_E_CPU1_SA_DQ<11>
  166  VSS71  POWER  = GND
  167  \dqs6_a_c||tdqs6_a_c||dqs6_a_t||tdqs6_a_t\  BI  = M_E_CPU1_SA_DQS_DN<6>
  168  \dqs6_a_t||tdqs6_a_t\  BI  = M_E_CPU1_SA_DQS_DP<6>
  169  VSS72  POWER  = GND
  170  DQ14_A  BI  = M_E_CPU1_SA_DQ<14>
  171  VSS73  POWER  = GND
  172  DQ15_A  BI  = M_E_CPU1_SA_DQ<15>
  173  VSS74  POWER  = GND
  174  DQ18_A  BI  = M_E_CPU1_SA_DQ<18>
  175  VSS75  POWER  = GND
  176  DQ19_A  BI  = M_E_CPU1_SA_DQ<19>
  177  VSS76  POWER  = GND
  178  \dqs7_a_c||tdqs7_a_c\  BI  = M_E_CPU1_SA_DQS_DN<7>
  179  \dqs7_a_t||tdqs7_a_t\  BI  = M_E_CPU1_SA_DQS_DP<7>
  180  VSS77  POWER  = GND
  181  DQ22_A  BI  = M_E_CPU1_SA_DQ<22>
  182  VSS78  POWER  = GND
  183  DQ23_A  BI  = M_E_CPU1_SA_DQ<23>
  184  VSS79  POWER  = GND
  185  DQ26_A  BI  = M_E_CPU1_SA_DQ<26>
  186  VSS80  POWER  = GND
  187  DQ27_A  BI  = M_E_CPU1_SA_DQ<27>
  188  VSS81  POWER  = GND
  189  \dqs8_a_c||tdqs8_a_c\  BI  = M_E_CPU1_SA_DQS_DN<8>
  190  \dqs8_a_t||tdqs8_a_t\  BI  = M_E_CPU1_SA_DQS_DP<8>
  191  VSS82  POWER  = GND
  192  DQ30_A  BI  = M_E_CPU1_SA_DQ<30>
  193  VSS83  POWER  = GND
  194  DQ31_A  BI  = M_E_CPU1_SA_DQ<31>
  195  VSS84  POWER  = GND
  196  CB2_A  BI  = M_E_CPU1_SA_CB<2>
  197  VSS85  POWER  = GND
  198  CB3_A  BI  = M_E_CPU1_SA_CB<3>
  199  VSS86  POWER  = GND
  200  \dqs9_a_c||tdqs9_a_c\  BI  = M_E_CPU1_SA_DQS_DN<9>
  201  \dqs9_a_t||tdqs9_a_t\  BI  = M_E_CPU1_SA_DQS_DP<9>
  202  VSS87  POWER  = GND
  203  CB6_A  BI  = M_E_CPU1_SA_CB<6>
  204  VSS88  POWER  = GND
  205  CB7_A  BI  = M_E_CPU1_SA_CB<7>
  206  VSS89  POWER  = GND
  207  RESET_N  IN  = RST_M_EF_CPU1_FPGA_N
  208  VSS90  POWER  = GND
  209  CS1_A_N  IN  = M_E_CPU1_SA_CS_N<3>
  210  VSS91  POWER  = GND
  211  CA1_A  IN  = M_E_CPU1_SA_CA<1>
  212  VSS92  POWER  = GND
  213  CA3_A  IN  = M_E_CPU1_SA_CA<3>
  214  VSS93  POWER  = GND
  215  CA5_A  IN  = M_E_CPU1_SA_CA<5>
  216  VSS94  POWER  = GND
  217  CK_T  IN  = M_E_CPU1_CLK_DP<1>
  218  CK_C  IN  = M_E_CPU1_CLK_DN<1>
  219  VSS95  POWER  = GND
  220  RFU4  TRI  = TP_CHE_CPU1_DIMM2_FRU_4
  221  CA1_B  IN  = M_E_CPU1_SB_CA<1>
  222  VSS96  POWER  = GND
  223  CA3_B  IN  = M_E_CPU1_SB_CA<3>
  224  VSS97  POWER  = GND
  225  CA5_B  IN  = M_E_CPU1_SB_CA<5>
  226  VSS98  POWER  = GND
  227  PAR_B  IN  = M_E_CPU1_SB_PAR
  228  VSS99  POWER  = GND
  229  CS1_B_N  IN  = M_E_CPU1_SB_CS_N<3>
  230  VSS100  POWER  = GND
  231  RFU5  TRI  = TP_CHE_CPU1_DIMM2_FRU_5
  232  RFU6  TRI  = TP_CHE_CPU1_DIMM2_FRU_6
  233  VSS101  POWER  = GND
  234  CB6_B  BI  = M_E_CPU1_SB_CB<6>
  235  VSS102  POWER  = GND
  236  CB7_B  BI  = M_E_CPU1_SB_CB<7>
  237  VSS103  POWER  = GND
  238  DQS4_B_C  BI  = M_E_CPU1_SB_DQS_DN<4>
  239  DQS4_B_T  BI  = M_E_CPU1_SB_DQS_DP<4>
  240  VSS104  POWER  = GND
  241  CB2_B  BI  = M_E_CPU1_SB_CB<2>
  242  VSS105  POWER  = GND
  243  CB3_B  BI  = M_E_CPU1_SB_CB<3>
  244  VSS106  POWER  = GND
  245  DQ2_B  BI  = M_E_CPU1_SB_DQ<2>
  246  VSS107  POWER  = GND
  247  DQ3_B  BI  = M_E_CPU1_SB_DQ<3>
  248  VSS108  POWER  = GND
  249  \dqs5_b_c||tdqs5_b_c\  BI  = M_E_CPU1_SB_DQS_DN<5>
  250  \dqs5_b_t||tdqs5_b_t\  BI  = M_E_CPU1_SB_DQS_DP<5>
  251  VSS109  POWER  = GND
  252  DQ6_B  BI  = M_E_CPU1_SB_DQ<6>
  253  VSS110  POWER  = GND
  254  DQ7_B  BI  = M_E_CPU1_SB_DQ<7>
  255  VSS111  POWER  = GND
  256  DQ10_B  BI  = M_E_CPU1_SB_DQ<10>
  257  VSS112  POWER  = GND
  258  DQ11_B  BI  = M_E_CPU1_SB_DQ<11>
  259  VSS113  POWER  = GND
  260  \dqs6_b_c||tdqs6_b_c\  BI  = M_E_CPU1_SB_DQS_DN<6>
  261  \dqs6_b_t||tdqs6_b_t\  BI  = M_E_CPU1_SB_DQS_DP<6>
  262  VSS114  POWER  = GND
  263  DQ14_B  BI  = M_E_CPU1_SB_DQ<14>
  264  VSS115  POWER  = GND
  265  DQ15_B  BI  = M_E_CPU1_SB_DQ<15>
  266  VSS116  POWER  = GND
  267  DQ18_B  BI  = M_E_CPU1_SB_DQ<18>
  268  VSS117  POWER  = GND
  269  DQ19_B  BI  = M_E_CPU1_SB_DQ<19>
  270  VSS118  POWER  = GND
  271  \dqs7_b_c||tdqs7_b_c\  BI  = M_E_CPU1_SB_DQS_DN<7>
  272  \dqs7_b_t||tdqs7_b_t\  BI  = M_E_CPU1_SB_DQS_DP<7>
  273  VSS119  POWER  = GND
  274  DQ22_B  BI  = M_E_CPU1_SB_DQ<22>
  275  VSS120  POWER  = GND
  276  DQ23_B  BI  = M_E_CPU1_SB_DQ<23>
  277  VSS121  POWER  = GND
  278  DQ26_B  BI  = M_E_CPU1_SB_DQ<26>
  279  VSS122  POWER  = GND
  280  DQ27_B  BI  = M_E_CPU1_SB_DQ<27>
  281  VSS123  POWER  = GND
  282  \dqs8_b_c||tdqs8_b_c\  BI  = M_E_CPU1_SB_DQS_DN<8>
  283  \dqs8_b_t||tdqs8_b_t\  BI  = M_E_CPU1_SB_DQS_DP<8>
  284  VSS124  POWER  = GND
  285  DQ30_B  BI  = M_E_CPU1_SB_DQ<30>
  286  VSS125  POWER  = GND
  287  DQ31_B  BI  = M_E_CPU1_SB_DQ<31>
  288  VSS126  POWER  = GND
  G1  G1  POWER  = GND
  G2  G2  POWER  = GND
  G3  G3  POWER  = GND
